# S9S_MB_2U (Grand Teton) — schematic netlist excerpt (pin names and nets, part order shuffled) for the footprints in the layout excerpt that follows; sources: Cadence DE-HDL packaged netlist, KiCad conversion of 03242023_DA0F0TMBIJ0_F0T_Motherboard_J_brd_V01_OCP.brd

PR665  Q_RES  10K 1% EMPTY  pkg 0402LF  page 292 : A = PVCCINFAON_CPU1_ATSEN ; B = GND
PC2203  Q_CAP  100PF 50V 5% EMPTY  pkg 0402  page 193 : A = P3V3_E1S_GATE_0_PU293 ; B = GND

(kicad_pcb
	(version 20260206)
	(generator "pcbnew")
	(generator_version "10.0")
	(general
		(thickness 1.6)
		(legacy_teardrops no)
	)
	(paper "A4")
	(title_block
		(title "03242023_DA0F0TMBIJ0_F0T_Motherboard_J_brd_V01_OCP.brd")
		(comment 1 "Grand Teton / footprints 446-447 of 6105")
	)
	(layers
		(0 "F.Cu" signal "TOP")
		(4 "In1.Cu" signal "GND")
		(6 "In2.Cu" signal "IN1")
		(8 "In3.Cu" signal "GND1")
		(10 "In4.Cu" signal "IN2")
		(12 "In5.Cu" signal "GND2")
		(14 "In6.Cu" signal "IN3")
		(16 "In7.Cu" signal "GND3")
		(18 "In8.Cu" signal "VCC")
		(20 "In9.Cu" signal "VCC1")
		(22 "In10.Cu" signal "GND4")
		(24 "In11.Cu" signal "IN4")
		(26 "In12.Cu" signal "GND5")
		(28 "In13.Cu" signal "IN5")
		(30 "In14.Cu" signal "GND6")
		(32 "In15.Cu" signal "IN6")
		(34 "In16.Cu" signal "GND7")
		(2 "B.Cu" signal "BOTTOM")
		(9 "F.Adhes" user "F.Adhesive")
		(11 "B.Adhes" user "B.Adhesive")
		(13 "F.Paste" user "Package Geometry/Pastemask Top")
		(15 "B.Paste" user "Package Geometry/Pastemask Bottom")
		(5 "F.SilkS" user "Ref Des/Silkscreen Top")
		(7 "B.SilkS" user "Ref Des/Silkscreen Bottom")
		(1 "F.Mask" user "Board Geometry/Soldermask Top")
		(3 "B.Mask" user "Board Geometry/Soldermask Bottom")
		(17 "Dwgs.User" user "User.Drawings")
		(19 "Cmts.User" user "User.Comments")
		(21 "Eco1.User" user "User.Eco1")
		(23 "Eco2.User" user "User.Eco2")
		(25 "Edge.Cuts" user "Board Geometry/Outline")
		(27 "Margin" user)
		(31 "F.CrtYd" user "Package Geometry/Place Bound Top")
		(29 "B.CrtYd" user "Package Geometry/Place Bound Bottom")
		(35 "F.Fab" user "Ref Des/Assembly Top")
		(33 "B.Fab" user "Ref Des/Assembly Bottom")
	)
	(footprint ""
		(layer "F.Cu")
		(at 24.768556 -130.26898 180)
		(property "Reference" "PR665"
			(at 0 0 180)
			(layer "F.SilkS")
			(hide yes)
			(effects
				(font
					(size 1.27 1.27)
				)
			)
		)
		(property "Value" ""
			(at 0 0 180)
			(layer "F.Fab")
			(effects
				(font
					(size 1.27 1.27)
				)
			)
		)
		(duplicate_pad_numbers_are_jumpers no)
		(fp_line
			(start 0.7874 0.4064)
			(end -0.7874 0.4064)
			(stroke
				(width 0.1524)
				(type default)
			)
			(layer "F.SilkS")
		)
		(fp_line
			(start 0.7874 -0.4064)
			(end 0.7874 0.4064)
			(stroke
				(width 0.1524)
				(type default)
			)
			(layer "F.SilkS")
		)
		(fp_line
			(start -0.7874 0.4064)
			(end -0.7874 -0.4064)
			(stroke
				(width 0.1524)
				(type default)
			)
			(layer "F.SilkS")
		)
		(fp_line
			(start -0.7874 -0.4064)
			(end 0.7874 -0.4064)
			(stroke
				(width 0.1524)
				(type default)
			)
			(layer "F.SilkS")
		)
		(fp_line
			(start 0.67945 0.3048)
			(end 0.120396 0.3048)
			(stroke
				(width 0.1)
				(type default)
			)
			(layer "F.Fab")
		)
		(fp_line
			(start 0.67945 -0.3048)
			(end 0.67945 0.3048)
			(stroke
				(width 0.1)
				(type default)
			)
			(layer "F.Fab")
		)
		(fp_line
			(start 0.12065 -0.2794)
			(end 0.12065 -0.3048)
			(stroke
				(width 0.1)
				(type default)
			)
			(layer "F.Fab")
		)
		(fp_line
			(start 0.12065 -0.3048)
			(end 0.67945 -0.3048)
			(stroke
				(width 0.1)
				(type default)
			)
			(layer "F.Fab")
		)
		(fp_line
			(start 0.120396 0.3048)
			(end 0.120396 0.2794)
			(stroke
				(width 0.1)
				(type default)
			)
			(layer "F.Fab")
		)
		(fp_line
			(start 0.120396 0.2794)
			(end -0.12065 0.2794)
			(stroke
				(width 0.1)
				(type default)
			)
			(layer "F.Fab")
		)
		(fp_line
			(start -0.12065 0.3048)
			(end -0.67945 0.3048)
			(stroke
				(width 0.1)
				(type default)
			)
			(layer "F.Fab")
		)
		(fp_line
			(start -0.12065 0.2794)
			(end -0.12065 0.3048)
			(stroke
				(width 0.1)
				(type default)
			)
			(layer "F.Fab")
		)
		(fp_line
			(start -0.12065 -0.2794)
			(end 0.12065 -0.2794)
			(stroke
				(width 0.1)
				(type default)
			)
			(layer "F.Fab")
		)
		(fp_line
			(start -0.12065 -0.305054)
			(end -0.12065 -0.2794)
			(stroke
				(width 0.1)
				(type default)
			)
			(layer "F.Fab")
		)
		(fp_line
			(start -0.67945 0.3048)
			(end -0.67945 -0.305054)
			(stroke
				(width 0.1)
				(type default)
			)
			(layer "F.Fab")
		)
		(fp_line
			(start -0.67945 -0.305054)
			(end -0.12065 -0.305054)
			(stroke
				(width 0.1)
				(type default)
			)
			(layer "F.Fab")
		)
		(pad "1" smd circle
			(at -0.40005 0 180)
			(size 0 0)
			(layers "F.Cu" "F.Mask" "F.Paste")
			(net "PVCCINFAON_CPU1_ATSEN")
		)
		(pad "2" smd circle
			(at 0.40005 0 180)
			(size 0 0)
			(layers "F.Cu" "F.Mask" "F.Paste")
			(net "GND")
		)
	)
	(footprint ""
		(layer "F.Cu")
		(at 198.41464 -68.026788)
		(property "Reference" "PC2203"
			(at 0 0 0)
			(layer "F.SilkS")
			(hide yes)
			(effects
				(font
					(size 1.27 1.27)
				)
			)
		)
		(property "Value" ""
			(at 0 0 0)
			(layer "F.Fab")
			(effects
				(font
					(size 1.27 1.27)
				)
			)
		)
		(duplicate_pad_numbers_are_jumpers no)
		(fp_line
			(start -0.7874 -0.4064)
			(end 0.7874 -0.4064)
			(stroke
				(width 0.1524)
				(type default)
			)
			(layer "F.SilkS")
		)
		(fp_line
			(start -0.7874 0.4064)
			(end -0.7874 -0.4064)
			(stroke
				(width 0.1524)
				(type default)
			)
			(layer "F.SilkS")
		)
		(fp_line
			(start 0.7874 -0.4064)
			(end 0.7874 0.4064)
			(stroke
				(width 0.1524)
				(type default)
			)
			(layer "F.SilkS")
		)
		(fp_line
			(start 0.7874 0.4064)
			(end -0.7874 0.4064)
			(stroke
				(width 0.1524)
				(type default)
			)
			(layer "F.SilkS")
		)
		(fp_line
			(start -0.67945 -0.305054)
			(end -0.12065 -0.305054)
			(stroke
				(width 0.1)
				(type default)
			)
			(layer "F.Fab")
		)
		(fp_line
			(start -0.67945 0.3048)
			(end -0.67945 -0.305054)
			(stroke
				(width 0.1)
				(type default)
			)
			(layer "F.Fab")
		)
		(fp_line
			(start -0.12065 -0.305054)
			(end -0.12065 -0.2794)
			(stroke
				(width 0.1)
				(type default)
			)
			(layer "F.Fab")
		)
		(fp_line
			(start -0.12065 -0.2794)
			(end 0.12065 -0.2794)
			(stroke
				(width 0.1)
				(type default)
			)
			(layer "F.Fab")
		)
		(fp_line
			(start -0.12065 0.2794)
			(end -0.12065 0.3048)
			(stroke
				(width 0.1)
				(type default)
			)
			(layer "F.Fab")
		)
		(fp_line
			(start -0.12065 0.3048)
			(end -0.67945 0.3048)
			(stroke
				(width 0.1)
				(type default)
			)
			(layer "F.Fab")
		)
		(fp_line
			(start 0.120396 0.2794)
			(end -0.12065 0.2794)
			(stroke
				(width 0.1)
				(type default)
			)
			(layer "F.Fab")
		)
		(fp_line
			(start 0.120396 0.3048)
			(end 0.120396 0.2794)
			(stroke
				(width 0.1)
				(type default)
			)
			(layer "F.Fab")
		)
		(fp_line
			(start 0.12065 -0.3048)
			(end 0.67945 -0.3048)
			(stroke
				(width 0.1)
				(type default)
			)
			(layer "F.Fab")
		)
		(fp_line
			(start 0.12065 -0.2794)
			(end 0.12065 -0.3048)
			(stroke
				(width 0.1)
				(type default)
			)
			(layer "F.Fab")
		)
		(fp_line
			(start 0.67945 -0.3048)
			(end 0.67945 0.3048)
			(stroke
				(width 0.1)
				(type default)
			)
			(layer "F.Fab")
		)
		(fp_line
			(start 0.67945 0.3048)
			(end 0.120396 0.3048)
			(stroke
				(width 0.1)
				(type default)
			)
			(layer "F.Fab")
		)
		(pad "1" smd circle
			(at -0.40005 0)
			(size 0 0)
			(layers "F.Cu" "F.Mask" "F.Paste")
			(net "P3V3_E1S_GATE_0_PU293")
		)
		(pad "2" smd circle
			(at 0.40005 0)
			(size 0 0)
			(layers "F.Cu" "F.Mask" "F.Paste")
			(net "GND")
		)
	)
)
